(kicad_pcb
	(version 20260206)
	(generator "pcbnew")
	(generator_version "10.0")
	(general
		(thickness 1.6)
		(legacy_teardrops no)
	)
	(paper "A4")
	(title_block
		(title "15969-1a.1015WZS0858.brd")
		(comment 1 "Tioga Pass / footprints 257-262 of 295")
	)
	(layers
		(0 "F.Cu" signal "TOP")
		(4 "In1.Cu" signal "L2GND")
		(6 "In2.Cu" signal "L3")
		(8 "In3.Cu" signal "L4")
		(10 "In4.Cu" signal "L5GND")
		(2 "B.Cu" signal "BOTTOM")
		(9 "F.Adhes" user "F.Adhesive")
		(11 "B.Adhes" user "B.Adhesive")
		(13 "F.Paste" user "Package Geometry/Pastemask Top")
		(15 "B.Paste" user "Package Geometry/Pastemask Bottom")
		(5 "F.SilkS" user "Ref Des/Silkscreen Top")
		(7 "B.SilkS" user "Ref Des/Silkscreen Bottom")
		(1 "F.Mask" user "Board Geometry/Soldermask Top")
		(3 "B.Mask" user "Board Geometry/Soldermask Bottom")
		(17 "Dwgs.User" user "User.Drawings")
		(19 "Cmts.User" user "User.Comments")
		(21 "Eco1.User" user "User.Eco1")
		(23 "Eco2.User" user "User.Eco2")
		(25 "Edge.Cuts" user "Board Geometry/Outline")
		(27 "Margin" user)
		(31 "F.CrtYd" user "Package Geometry/Place Bound Top")
		(29 "B.CrtYd" user "Package Geometry/Place Bound Bottom")
		(35 "F.Fab" user "Ref Des/Assembly Top")
		(33 "B.Fab" user "Ref Des/Assembly Bottom")
	)
	(footprint ""
		(layer "B.Cu")
		(at 41.6814 -1.5367 180)
		(property "Reference" "R28"
			(at 0 0 0)
			(layer "B.SilkS")
			(hide yes)
			(effects
				(font
					(size 1.27 1.27)
				)
				(justify mirror)
			)
		)
		(property "Value" "0R2F-1-GP"
			(at -0.064008 -3.993896 180)
			(unlocked yes)
			(layer "B.Fab")
			(hide yes)
			(effects
				(font
					(size 1.016 1.016)
					(thickness 0.1524)
				)
				(justify mirror)
			)
		)
		(property "Device Type" "R402H16"
			(at -0.064008 -5.517896 180)
			(unlocked yes)
			(layer "B.Fab")
			(hide yes)
			(effects
				(font
					(size 1.016 1.016)
					(thickness 0.1524)
				)
				(justify mirror)
			)
		)
		(duplicate_pad_numbers_are_jumpers no)
		(fp_line
			(start 0.508 -0.9398)
			(end 0.508 0.9398)
			(stroke
				(width 0.1524)
				(type default)
			)
			(layer "B.SilkS")
		)
		(fp_line
			(start -0.508 -0.9398)
			(end 0.508 -0.9398)
			(stroke
				(width 0.1524)
				(type default)
			)
			(layer "B.SilkS")
		)
		(fp_rect
			(start 0.508 0.9398)
			(end -0.508 -0.9398)
			(stroke
				(width 0)
				(type default)
			)
			(fill no)
			(layer "B.CrtYd")
		)
		(fp_rect
			(start 0.508 0.9398)
			(end -0.508 -0.9398)
			(stroke
				(width 0)
				(type default)
			)
			(fill no)
			(layer "B.Fab")
		)
		(pad "1" smd custom
			(at 0 -0.4445)
			(size 0.1397 0.1397)
			(layers "B.Cu" "B.Mask" "B.Paste")
			(net "SMDAT_BMC_SLOT2")
			(options
				(clearance outline)
				(anchor circle)
			)
			(primitives
				(gr_poly
					(pts
						(arc
							(start -0.1778 0.2794)
							(mid -0.249642 0.249642)
							(end -0.2794 0.1778)
						)
						(arc
							(start -0.2794 -0.1778)
							(mid -0.249642 -0.249642)
							(end -0.1778 -0.2794)
						)
						(arc
							(start 0.1778 -0.2794)
							(mid 0.249642 -0.249642)
							(end 0.2794 -0.1778)
						)
						(arc
							(start 0.2794 0.1778)
							(mid 0.249642 0.249642)
							(end 0.1778 0.2794)
						)
					)
					(width 0)
					(fill yes)
				)
			)
		)
		(pad "2" smd custom
			(at 0 0.4445)
			(size 0.1397 0.1397)
			(layers "B.Cu" "B.Mask" "B.Paste")
			(net "SMDAT_BMC_SLOT2_R")
			(options
				(clearance outline)
				(anchor circle)
			)
			(primitives
				(gr_poly
					(pts
						(arc
							(start -0.1778 0.2794)
							(mid -0.249642 0.249642)
							(end -0.2794 0.1778)
						)
						(arc
							(start -0.2794 -0.1778)
							(mid -0.249642 -0.249642)
							(end -0.1778 -0.2794)
						)
						(arc
							(start 0.1778 -0.2794)
							(mid 0.249642 -0.249642)
							(end 0.2794 -0.1778)
						)
						(arc
							(start 0.2794 0.1778)
							(mid 0.249642 0.249642)
							(end 0.1778 0.2794)
						)
					)
					(width 0)
					(fill yes)
				)
			)
		)
	)
	(footprint ""
		(layer "B.Cu")
		(at 26.8478 -21.0312 90)
		(property "Reference" "R170"
			(at 0 0 90)
			(layer "B.SilkS")
			(hide yes)
			(effects
				(font
					(size 1.27 1.27)
				)
				(justify mirror)
			)
		)
		(property "Value" "0R2F-1-GP"
			(at -0.064008 -3.993896 90)
			(unlocked yes)
			(layer "B.Fab")
			(hide yes)
			(effects
				(font
					(size 1.016 1.016)
					(thickness 0.1524)
				)
				(justify mirror)
			)
		)
		(property "Device Type" "R402H16"
			(at -0.064008 -5.517896 90)
			(unlocked yes)
			(layer "B.Fab")
			(hide yes)
			(effects
				(font
					(size 1.016 1.016)
					(thickness 0.1524)
				)
				(justify mirror)
			)
		)
		(duplicate_pad_numbers_are_jumpers no)
		(fp_line
			(start 0.508 -0.9398)
			(end 0.508 0.9398)
			(stroke
				(width 0.1524)
				(type default)
			)
			(layer "B.SilkS")
		)
		(fp_line
			(start -0.508 -0.9398)
			(end 0.508 -0.9398)
			(stroke
				(width 0.1524)
				(type default)
			)
			(layer "B.SilkS")
		)
		(fp_rect
			(start 0.508 0.9398)
			(end -0.508 -0.9398)
			(stroke
				(width 0)
				(type default)
			)
			(fill no)
			(layer "B.CrtYd")
		)
		(fp_rect
			(start 0.508 0.9398)
			(end -0.508 -0.9398)
			(stroke
				(width 0)
				(type default)
			)
			(fill no)
			(layer "B.Fab")
		)
		(pad "1" smd custom
			(at 0 -0.4445 270)
			(size 0.1397 0.1397)
			(layers "B.Cu" "B.Mask" "B.Paste")
			(net "SMB_VMONITOR_SLOT3_ALERT_N")
			(options
				(clearance outline)
				(anchor circle)
			)
			(primitives
				(gr_poly
					(pts
						(arc
							(start -0.1778 0.2794)
							(mid -0.249642 0.249642)
							(end -0.2794 0.1778)
						)
						(arc
							(start -0.2794 -0.1778)
							(mid -0.249642 -0.249642)
							(end -0.1778 -0.2794)
						)
						(arc
							(start 0.1778 -0.2794)
							(mid 0.249642 -0.249642)
							(end 0.2794 -0.1778)
						)
						(arc
							(start 0.2794 0.1778)
							(mid 0.249642 0.249642)
							(end 0.1778 0.2794)
						)
					)
					(width 0)
					(fill yes)
				)
			)
		)
		(pad "2" smd custom
			(at 0 0.4445 270)
			(size 0.1397 0.1397)
			(layers "B.Cu" "B.Mask" "B.Paste")
			(net "SMB_BMC_DEVICE_ALERT_N")
			(options
				(clearance outline)
				(anchor circle)
			)
			(primitives
				(gr_poly
					(pts
						(arc
							(start -0.1778 0.2794)
							(mid -0.249642 0.249642)
							(end -0.2794 0.1778)
						)
						(arc
							(start -0.2794 -0.1778)
							(mid -0.249642 -0.249642)
							(end -0.1778 -0.2794)
						)
						(arc
							(start 0.1778 -0.2794)
							(mid 0.249642 -0.249642)
							(end 0.2794 -0.1778)
						)
						(arc
							(start 0.2794 0.1778)
							(mid 0.249642 0.249642)
							(end 0.1778 0.2794)
						)
					)
					(width 0)
					(fill yes)
				)
			)
		)
	)
	(footprint ""
		(layer "B.Cu")
		(at 129.032 -24.9936 180)
		(property "Reference" "R169"
			(at 0 0 0)
			(layer "B.SilkS")
			(hide yes)
			(effects
				(font
					(size 1.27 1.27)
				)
				(justify mirror)
			)
		)
		(property "Value" "0R2F-1-GP"
			(at -0.064008 -3.993896 180)
			(unlocked yes)
			(layer "B.Fab")
			(hide yes)
			(effects
				(font
					(size 1.016 1.016)
					(thickness 0.1524)
				)
				(justify mirror)
			)
		)
		(property "Device Type" "R402H16"
			(at -0.064008 -5.517896 180)
			(unlocked yes)
			(layer "B.Fab")
			(hide yes)
			(effects
				(font
					(size 1.016 1.016)
					(thickness 0.1524)
				)
				(justify mirror)
			)
		)
		(duplicate_pad_numbers_are_jumpers no)
		(fp_line
			(start 0.508 -0.9398)
			(end 0.508 0.9398)
			(stroke
				(width 0.1524)
				(type default)
			)
			(layer "B.SilkS")
		)
		(fp_line
			(start -0.508 -0.9398)
			(end 0.508 -0.9398)
			(stroke
				(width 0.1524)
				(type default)
			)
			(layer "B.SilkS")
		)
		(fp_rect
			(start 0.508 0.9398)
			(end -0.508 -0.9398)
			(stroke
				(width 0)
				(type default)
			)
			(fill no)
			(layer "B.CrtYd")
		)
		(fp_rect
			(start 0.508 0.9398)
			(end -0.508 -0.9398)
			(stroke
				(width 0)
				(type default)
			)
			(fill no)
			(layer "B.Fab")
		)
		(pad "1" smd custom
			(at 0 -0.4445)
			(size 0.1397 0.1397)
			(layers "B.Cu" "B.Mask" "B.Paste")
			(net "SMDAT_USB_HUB")
			(options
				(clearance outline)
				(anchor circle)
			)
			(primitives
				(gr_poly
					(pts
						(arc
							(start -0.1778 0.2794)
							(mid -0.249642 0.249642)
							(end -0.2794 0.1778)
						)
						(arc
							(start -0.2794 -0.1778)
							(mid -0.249642 -0.249642)
							(end -0.1778 -0.2794)
						)
						(arc
							(start 0.1778 -0.2794)
							(mid 0.249642 -0.249642)
							(end 0.2794 -0.1778)
						)
						(arc
							(start 0.2794 0.1778)
							(mid 0.249642 0.249642)
							(end 0.1778 0.2794)
						)
					)
					(width 0)
					(fill yes)
				)
			)
		)
		(pad "2" smd custom
			(at 0 0.4445)
			(size 0.1397 0.1397)
			(layers "B.Cu" "B.Mask" "B.Paste")
			(net "SMDAT_PCH_DEVICE")
			(options
				(clearance outline)
				(anchor circle)
			)
			(primitives
				(gr_poly
					(pts
						(arc
							(start -0.1778 0.2794)
							(mid -0.249642 0.249642)
							(end -0.2794 0.1778)
						)
						(arc
							(start -0.2794 -0.1778)
							(mid -0.249642 -0.249642)
							(end -0.1778 -0.2794)
						)
						(arc
							(start 0.1778 -0.2794)
							(mid 0.249642 -0.249642)
							(end 0.2794 -0.1778)
						)
						(arc
							(start 0.2794 0.1778)
							(mid 0.249642 0.249642)
							(end 0.1778 0.2794)
						)
					)
					(width 0)
					(fill yes)
				)
			)
		)
	)
	(footprint ""
		(layer "B.Cu")
		(at 123.2916 -2.921)
		(property "Reference" "C59"
			(at 0 0 0)
			(layer "B.SilkS")
			(hide yes)
			(effects
				(font
					(size 1.27 1.27)
				)
				(justify mirror)
			)
		)
		(property "Value" "SCD1U16V2KX-3GP"
			(at -1.1811 -2.7051 0)
			(unlocked yes)
			(layer "B.Fab")
			(hide yes)
			(effects
				(font
					(size 1.016 1.016)
					(thickness 0.1524)
				)
				(justify mirror)
			)
		)
		(property "Device Type" "C402H22"
			(at -1.1811 -4.2291 0)
			(unlocked yes)
			(layer "B.Fab")
			(hide yes)
			(effects
				(font
					(size 1.016 1.016)
					(thickness 0.1524)
				)
				(justify mirror)
			)
		)
		(duplicate_pad_numbers_are_jumpers no)
		(fp_rect
			(start 0.4318 0.9525)
			(end -0.4318 -0.9525)
			(stroke
				(width 0)
				(type default)
			)
			(fill no)
			(layer "B.CrtYd")
		)
		(fp_rect
			(start 0.4318 0.9525)
			(end -0.4318 -0.9525)
			(stroke
				(width 0)
				(type default)
			)
			(fill no)
			(layer "B.Fab")
		)
		(pad "1" smd custom
			(at 0 -0.4445 180)
			(size 0.1524 0.1524)
			(layers "B.Cu" "B.Mask" "B.Paste")
			(net "P3V3_STBY")
			(options
				(clearance outline)
				(anchor circle)
			)
			(primitives
				(gr_poly
					(pts
						(arc
							(start 0.3048 0.2032)
							(mid 0.275042 0.275042)
							(end 0.2032 0.3048)
						)
						(arc
							(start -0.2032 0.3048)
							(mid -0.275042 0.275042)
							(end -0.3048 0.2032)
						)
						(arc
							(start -0.3048 -0.2032)
							(mid -0.275042 -0.275042)
							(end -0.2032 -0.3048)
						)
						(arc
							(start 0.2032 -0.3048)
							(mid 0.275042 -0.275042)
							(end 0.3048 -0.2032)
						)
					)
					(width 0)
					(fill yes)
				)
			)
		)
		(pad "2" smd custom
			(at 0 0.4445 180)
			(size 0.1524 0.1524)
			(layers "B.Cu" "B.Mask" "B.Paste")
			(net "GND")
			(options
				(clearance outline)
				(anchor circle)
			)
			(primitives
				(gr_poly
					(pts
						(arc
							(start 0.3048 0.2032)
							(mid 0.275042 0.275042)
							(end 0.2032 0.3048)
						)
						(arc
							(start -0.2032 0.3048)
							(mid -0.275042 0.275042)
							(end -0.3048 0.2032)
						)
						(arc
							(start -0.3048 -0.2032)
							(mid -0.275042 -0.275042)
							(end -0.2032 -0.3048)
						)
						(arc
							(start 0.2032 -0.3048)
							(mid 0.275042 -0.275042)
							(end 0.3048 -0.2032)
						)
					)
					(width 0)
					(fill yes)
				)
			)
		)
	)
	(footprint ""
		(layer "B.Cu")
		(at 17.2339 -28.8544 -135)
		(property "Reference" "R109"
			(at 0 0 45)
			(layer "B.SilkS")
			(hide yes)
			(effects
				(font
					(size 1.27 1.27)
				)
				(justify mirror)
			)
		)
		(property "Value" "D001R6F-L-GP"
			(at 0.126442 -3.733916 225)
			(unlocked yes)
			(layer "B.Fab")
			(hide yes)
			(effects
				(font
					(size 1.016 1.016)
					(thickness 0.1524)
				)
				(justify mirror)
			)
		)
		(property "Device Type" "R1206H36"
			(at 0.126801 -5.257685 225)
			(unlocked yes)
			(layer "B.Fab")
			(hide yes)
			(effects
				(font
					(size 1.016 1.016)
					(thickness 0.1524)
				)
				(justify mirror)
			)
		)
		(duplicate_pad_numbers_are_jumpers no)
		(fp_line
			(start 1.016026 2.235186)
			(end 1.016026 -2.235186)
			(stroke
				(width 0.1524)
				(type default)
			)
			(layer "B.SilkS")
		)
		(fp_line
			(start -1.016206 2.235365)
			(end 1.016026 2.235186)
			(stroke
				(width 0.1524)
				(type default)
			)
			(layer "B.SilkS")
		)
		(fp_line
			(start 1.016026 -2.235186)
			(end -1.016385 -2.235186)
			(stroke
				(width 0.1524)
				(type default)
			)
			(layer "B.SilkS")
		)
		(fp_line
			(start -1.016385 -2.235186)
			(end -1.016206 2.235365)
			(stroke
				(width 0.1524)
				(type default)
			)
			(layer "B.SilkS")
		)
		(fp_poly
			(pts
				(xy -0.800059 1.600102) (xy -0.80006 -1.600298) (xy 0.800141 -1.600299) (xy 0.800141 1.600102)
			)
			(stroke
				(width 0)
				(type default)
			)
			(fill no)
			(layer "B.CrtYd")
		)
		(fp_poly
			(pts
				(xy 1.091999 2.311518) (xy 1.09164 -2.311518) (xy -1.092179 -2.311338) (xy -1.092179 1.58753) (xy -0.8005 1.58753)
				(xy -0.80032 -1.600282) (xy 0.800141 -1.600102) (xy 0.800141 1.600102) (xy -1.092179 1.600102) (xy -1.092179 2.311338)
			)
			(stroke
				(width 0)
				(type default)
			)
			(fill no)
			(layer "B.CrtYd")
		)
		(fp_poly
			(pts
				(xy -1.092401 2.311518) (xy -1.092401 -2.311282) (xy 1.091999 -2.311282) (xy 1.091999 2.311518)
			)
			(stroke
				(width 0)
				(type default)
			)
			(fill no)
			(layer "B.Fab")
		)
		(pad "1" smd rect
			(at 0 -1.397 45)
			(size 1.651 1.27)
			(layers "B.Cu" "B.Mask" "B.Paste")
			(net "P12V")
		)
		(pad "2" smd rect
			(at 0 1.397 45)
			(size 1.651 1.27)
			(layers "B.Cu" "B.Mask" "B.Paste")
			(net "P12V_ATX")
		)
	)
	(footprint ""
		(layer "B.Cu")
		(at 130.3528 -10.4394 -90)
		(property "Reference" "R21"
			(at 0 0 90)
			(layer "B.SilkS")
			(hide yes)
			(effects
				(font
					(size 1.27 1.27)
				)
				(justify mirror)
			)
		)
		(property "Value" "4K7R2F-GP"
			(at -0.064008 -3.993896 270)
			(unlocked yes)
			(layer "B.Fab")
			(hide yes)
			(effects
				(font
					(size 1.016 1.016)
					(thickness 0.1524)
				)
				(justify mirror)
			)
		)
		(property "Device Type" "R402H16"
			(at -0.064008 -5.517896 270)
			(unlocked yes)
			(layer "B.Fab")
			(hide yes)
			(effects
				(font
					(size 1.016 1.016)
					(thickness 0.1524)
				)
				(justify mirror)
			)
		)
		(duplicate_pad_numbers_are_jumpers no)
		(fp_line
			(start -0.508 -0.9398)
			(end 0.508 -0.9398)
			(stroke
				(width 0.1524)
				(type default)
			)
			(layer "B.SilkS")
		)
		(fp_line
			(start 0.508 -0.9398)
			(end 0.508 0.9398)
			(stroke
				(width 0.1524)
				(type default)
			)
			(layer "B.SilkS")
		)
		(fp_rect
			(start 0.508 0.9398)
			(end -0.508 -0.9398)
			(stroke
				(width 0)
				(type default)
			)
			(fill no)
			(layer "B.CrtYd")
		)
		(fp_rect
			(start 0.508 0.9398)
			(end -0.508 -0.9398)
			(stroke
				(width 0)
				(type default)
			)
			(fill no)
			(layer "B.Fab")
		)
		(pad "1" smd custom
			(at 0 -0.4445 90)
			(size 0.1397 0.1397)
			(layers "B.Cu" "B.Mask" "B.Paste")
			(net "P3V3_STBY")
			(options
				(clearance outline)
				(anchor circle)
			)
			(primitives
				(gr_poly
					(pts
						(arc
							(start -0.1778 0.2794)
							(mid -0.249642 0.249642)
							(end -0.2794 0.1778)
						)
						(arc
							(start -0.2794 -0.1778)
							(mid -0.249642 -0.249642)
							(end -0.1778 -0.2794)
						)
						(arc
							(start 0.1778 -0.2794)
							(mid 0.249642 -0.249642)
							(end 0.2794 -0.1778)
						)
						(arc
							(start 0.2794 0.1778)
							(mid 0.249642 0.249642)
							(end 0.1778 0.2794)
						)
					)
					(width 0)
					(fill yes)
				)
			)
		)
		(pad "2" smd custom
			(at 0 0.4445 90)
			(size 0.1397 0.1397)
			(layers "B.Cu" "B.Mask" "B.Paste")
			(net "SMCLK_PCH_SLOT3")
			(options
				(clearance outline)
				(anchor circle)
			)
			(primitives
				(gr_poly
					(pts
						(arc
							(start -0.1778 0.2794)
							(mid -0.249642 0.249642)
							(end -0.2794 0.1778)
						)
						(arc
							(start -0.2794 -0.1778)
							(mid -0.249642 -0.249642)
							(end -0.1778 -0.2794)
						)
						(arc
							(start 0.1778 -0.2794)
							(mid 0.249642 -0.249642)
							(end 0.2794 -0.1778)
						)
						(arc
							(start 0.2794 0.1778)
							(mid 0.249642 0.249642)
							(end 0.1778 0.2794)
						)
					)
					(width 0)
					(fill yes)
				)
			)
		)
	)
)
